(kicad_pcb
	(version 20241229)
	(generator "pcbnew")
	(generator_version "9.0")
	(general
		(thickness 1.552)
		(legacy_teardrops no)
	)
	(paper "A4")
	(title_block
		(date "2023-07-25")
		(rev "1.1.4")
		(comment 9 "footprints 314-317 of 379")
	)
	(layers
		(0 "F.Cu" signal)
		(4 "In1.Cu" signal)
		(6 "In2.Cu" signal)
		(8 "In3.Cu" signal)
		(10 "In4.Cu" signal)
		(12 "In5.Cu" signal)
		(14 "In6.Cu" signal)
		(2 "B.Cu" signal)
		(9 "F.Adhes" user "F.Adhesive")
		(11 "B.Adhes" user "B.Adhesive")
		(13 "F.Paste" user)
		(15 "B.Paste" user)
		(5 "F.SilkS" user "F.Silkscreen")
		(7 "B.SilkS" user "B.Silkscreen")
		(1 "F.Mask" user)
		(3 "B.Mask" user)
		(17 "Dwgs.User" user "User.Drawings")
		(19 "Cmts.User" user "User.Comments")
		(21 "Eco1.User" user "User.Eco1")
		(23 "Eco2.User" user "User.Eco2")
		(25 "Edge.Cuts" user)
		(27 "Margin" user)
		(31 "F.CrtYd" user "F.Courtyard")
		(29 "B.CrtYd" user "B.Courtyard")
		(35 "F.Fab" user)
		(33 "B.Fab" user)
	)
	(footprint "antmicro-footprints:C_0402_1005Metric"
		(layer "B.Cu")
		(at 93.08 74.06 180)
		(descr "Capacitor SMD 0402")
		(tags "capacitor SMD 0402")
		(property "Reference" "C66"
			(at -1.05 0.62 0)
			(layer "B.SilkS")
			(effects
				(font
					(size 0.65 0.65)
					(thickness 0.15)
				)
				(justify left bottom mirror)
			)
		)
		(property "Value" "C_100n_0402"
			(at 0 -1.4 0)
			(layer "B.Fab")
			(hide yes)
			(effects
				(font
					(size 0.7 0.7)
					(thickness 0.15)
				)
				(justify left bottom mirror)
			)
		)
		(property "Datasheet" "https://www.murata.com/products/productdetail?partno=GRM155R61H104KE14%23"
			(at 0 0 180)
			(layer "F.Fab")
			(hide yes)
			(effects
				(font
					(size 1.27 1.27)
					(thickness 0.15)
				)
			)
		)
		(property "Description" "SMD Multilayer Ceramic Capacitor, 0.1 µF, 50 V, 0402 [1005 Metric], ± 10%, X5R, GRM Series"
			(at 0 0 180)
			(layer "F.Fab")
			(hide yes)
			(effects
				(font
					(size 1.27 1.27)
					(thickness 0.15)
				)
			)
		)
		(property "Author" "Antmicro"
			(at 186.16 148.12 0)
			(layer "B.Fab")
			(hide yes)
			(effects
				(font
					(size 1 1)
					(thickness 0.15)
				)
				(justify mirror)
			)
		)
		(property "Dielectric" "X5R"
			(at 186.16 148.12 0)
			(layer "B.Fab")
			(hide yes)
			(effects
				(font
					(size 1 1)
					(thickness 0.15)
				)
				(justify mirror)
			)
		)
		(property "License" "Apache-2.0"
			(at 186.16 148.12 0)
			(layer "B.Fab")
			(hide yes)
			(effects
				(font
					(size 1 1)
					(thickness 0.15)
				)
				(justify mirror)
			)
		)
		(property "MPN" "GRM155R61H104KE14D"
			(at 186.16 148.12 0)
			(layer "B.Fab")
			(hide yes)
			(effects
				(font
					(size 1 1)
					(thickness 0.15)
				)
				(justify mirror)
			)
		)
		(property "Manufacturer" "Murata"
			(at 186.16 148.12 0)
			(layer "B.Fab")
			(hide yes)
			(effects
				(font
					(size 1 1)
					(thickness 0.15)
				)
				(justify mirror)
			)
		)
		(property "Val" "100n"
			(at 186.16 148.12 0)
			(layer "B.Fab")
			(hide yes)
			(effects
				(font
					(size 1 1)
					(thickness 0.15)
				)
				(justify mirror)
			)
		)
		(property "Voltage" "50V"
			(at 186.16 148.12 0)
			(layer "B.Fab")
			(hide yes)
			(effects
				(font
					(size 1 1)
					(thickness 0.15)
				)
				(justify mirror)
			)
		)
		(sheetname "/SDI/")
		(sheetfile "sdi.kicad_sch")
		(attr smd)
		(fp_rect
			(start -0.925 0.47)
			(end 0.925 -0.47)
			(stroke
				(width 0.05)
				(type default)
			)
			(fill no)
			(layer "B.CrtYd")
		)
		(fp_line
			(start 0.504 0.25)
			(end 0.504 -0.248)
			(stroke
				(width 0.15)
				(type solid)
			)
			(layer "B.Fab")
		)
		(fp_line
			(start 0.504 -0.248)
			(end -0.494 -0.248)
			(stroke
				(width 0.15)
				(type solid)
			)
			(layer "B.Fab")
		)
		(fp_line
			(start -0.494 0.25)
			(end 0.504 0.25)
			(stroke
				(width 0.15)
				(type solid)
			)
			(layer "B.Fab")
		)
		(fp_line
			(start -0.494 -0.248)
			(end -0.494 0.25)
			(stroke
				(width 0.15)
				(type solid)
			)
			(layer "B.Fab")
		)
		(fp_text user "License: Apache-2.0"
			(at -0.939 -5.799 0)
			(layer "B.Fab")
			(effects
				(font
					(size 0.7 0.7)
					(thickness 0.15)
				)
				(justify left bottom mirror)
			)
		)
		(fp_text user "${REFERENCE}"
			(at -0.939 -4.599 0)
			(layer "B.Fab")
			(effects
				(font
					(size 0.7 0.7)
					(thickness 0.15)
				)
				(justify left bottom mirror)
			)
		)
		(fp_text user "Author: Antmicro"
			(at -0.939 -3.399 0)
			(layer "B.Fab")
			(effects
				(font
					(size 0.7 0.7)
					(thickness 0.15)
				)
				(justify left bottom mirror)
			)
		)
		(pad "1" smd roundrect
			(at -0.48 0 180)
			(size 0.59 0.64)
			(layers "B.Cu" "B.Mask" "B.Paste")
			(roundrect_rratio 0.25)
			(net 1 "GND")
			(pintype "passive")
		)
		(pad "2" smd roundrect
			(at 0.48 0 180)
			(size 0.59 0.64)
			(layers "B.Cu" "B.Mask" "B.Paste")
			(roundrect_rratio 0.25)
			(net 3 "+1V2")
			(pintype "passive")
		)
	)
	(footprint "antmicro-footprints:C_0201"
		(layer "B.Cu")
		(at 127.57 93.94 45)
		(descr "Capacitor SMD 0201")
		(tags "capacitor SMD 0201")
		(property "Reference" "C104"
			(at 1.835463 -14.761374 45)
			(layer "B.SilkS")
			(effects
				(font
					(size 0.65 0.65)
					(thickness 0.15)
				)
				(justify right bottom mirror)
			)
		)
		(property "Value" "C_100n_0201"
			(at 0 -1.399999 45)
			(layer "B.Fab")
			(hide yes)
			(effects
				(font
					(size 0.7 0.7)
					(thickness 0.15)
				)
				(justify right bottom mirror)
			)
		)
		(property "Datasheet" "https://www.yageo.com/en/Chart/Download/pdf/CC0201KRX6S5BB104"
			(at 0 0 45)
			(layer "F.Fab")
			(hide yes)
			(effects
				(font
					(size 1.27 1.27)
					(thickness 0.15)
				)
			)
		)
		(property "Description" "SMD Multilayer Ceramic Capacitor, 0.1 µF, 6.3 V, 0201 [0603 Metric], ± 10%, X6S, CC Series"
			(at 0 0 45)
			(layer "F.Fab")
			(hide yes)
			(effects
				(font
					(size 1.27 1.27)
					(thickness 0.15)
				)
			)
		)
		(property "Author" "Antmicro"
			(at 103.789999 -62.691223 0)
			(layer "B.Fab")
			(hide yes)
			(effects
				(font
					(size 1 1)
					(thickness 0.15)
				)
				(justify mirror)
			)
		)
		(property "Dielectric" ""
			(at 103.789999 -62.691223 0)
			(layer "B.Fab")
			(hide yes)
			(effects
				(font
					(size 1 1)
					(thickness 0.15)
				)
				(justify mirror)
			)
		)
		(property "License" "Apache-2.0"
			(at 103.789999 -62.691223 0)
			(layer "B.Fab")
			(hide yes)
			(effects
				(font
					(size 1 1)
					(thickness 0.15)
				)
				(justify mirror)
			)
		)
		(property "MPN" "CC0201KRX6S5BB104"
			(at 103.789999 -62.691223 0)
			(layer "B.Fab")
			(hide yes)
			(effects
				(font
					(size 1 1)
					(thickness 0.15)
				)
				(justify mirror)
			)
		)
		(property "Manufacturer" "YAGEO"
			(at 103.789999 -62.691223 0)
			(layer "B.Fab")
			(hide yes)
			(effects
				(font
					(size 1 1)
					(thickness 0.15)
				)
				(justify mirror)
			)
		)
		(property "Val" "100n"
			(at 103.789999 -62.691223 0)
			(layer "B.Fab")
			(hide yes)
			(effects
				(font
					(size 1 1)
					(thickness 0.15)
				)
				(justify mirror)
			)
		)
		(property "Voltage" ""
			(at 103.789999 -62.691223 0)
			(layer "B.Fab")
			(hide yes)
			(effects
				(font
					(size 1 1)
					(thickness 0.15)
				)
				(justify mirror)
			)
		)
		(property "Public" "False"
			(at 0 0 45)
			(unlocked yes)
			(layer "B.Fab")
			(hide yes)
			(effects
				(font
					(size 1 1)
					(thickness 0.15)
				)
				(justify mirror)
			)
		)
		(sheetname "/FPGA Power/")
		(sheetfile "FPGA_Power.kicad_sch")
		(attr smd)
		(fp_poly
			(pts
				(xy -0.7 0.35) (xy 0.7 0.35) (xy 0.7 -0.35) (xy -0.7 -0.35)
			)
			(stroke
				(width 0.05)
				(type default)
			)
			(fill no)
			(layer "B.CrtYd")
		)
		(fp_poly
			(pts
				(xy 0.3 -0.15) (xy -0.301 -0.15) (xy -0.301 0.149) (xy 0.3 0.149)
			)
			(stroke
				(width 0.15)
				(type solid)
			)
			(fill no)
			(layer "B.Fab")
		)
		(fp_text user "License: Apache-2.0"
			(at -0.72 -4.4 225)
			(layer "B.Fab")
			(effects
				(font
					(size 0.7 0.7)
					(thickness 0.15)
				)
				(justify left bottom mirror)
			)
		)
		(fp_text user "Author: Antmicro"
			(at -0.72 -5.400001 225)
			(layer "B.Fab")
			(effects
				(font
					(size 0.7 0.7)
					(thickness 0.15)
				)
				(justify left bottom mirror)
			)
		)
		(fp_text user "${REFERENCE}"
			(at -0.72 -3.4 225)
			(layer "B.Fab")
			(effects
				(font
					(size 0.7 0.7)
					(thickness 0.15)
				)
				(justify left bottom mirror)
			)
		)
		(pad "" smd roundrect
			(at -0.349 0.002 45)
			(size 0.318 0.36)
			(layers "B.Paste")
			(roundrect_rratio 0.25)
		)
		(pad "" smd roundrect
			(at 0.341 0.002 45)
			(size 0.318 0.36)
			(layers "B.Paste")
			(roundrect_rratio 0.25)
		)
		(pad "1" smd roundrect
			(at -0.321 0.002 45)
			(size 0.46 0.4)
			(layers "B.Cu" "B.Mask")
			(roundrect_rratio 0.25)
			(net 1 "GND")
			(pintype "passive")
		)
		(pad "2" smd roundrect
			(at 0.32 0.002 45)
			(size 0.46 0.4)
			(layers "B.Cu" "B.Mask")
			(roundrect_rratio 0.25)
			(net 4 "1V0_Power")
			(pintype "passive")
		)
	)
	(footprint "antmicro-footprints:FB_0603_1608Metric"
		(layer "B.Cu")
		(at 130.75 81.06)
		(property "Reference" "FB1"
			(at 1.03 1.58 180)
			(layer "B.SilkS")
			(effects
				(font
					(size 0.65 0.65)
					(thickness 0.15)
				)
				(justify left bottom mirror)
			)
		)
		(property "Value" "FB_120Z_2A_0603"
			(at 0 -1.5 180)
			(layer "B.Fab")
			(hide yes)
			(effects
				(font
					(size 0.7 0.7)
					(thickness 0.15)
				)
				(justify left bottom mirror)
			)
		)
		(property "Datasheet" "https://www.murata.com/en-us/products/productdata/8796738650142/ENFA0003.pdf"
			(at 0 0 0)
			(layer "F.Fab")
			(hide yes)
			(effects
				(font
					(size 1.27 1.27)
					(thickness 0.15)
				)
			)
		)
		(property "Description" "Ferrite Bead, 0603 [1608 Metric], 120 ohm, 2 A, BLM18P, 0.05 ohm, ± 25%, DC power line"
			(at 0 0 0)
			(layer "F.Fab")
			(hide yes)
			(effects
				(font
					(size 1.27 1.27)
					(thickness 0.15)
				)
			)
		)
		(property "Author" "Antmicro"
			(at 0 0 0)
			(layer "B.Fab")
			(hide yes)
			(effects
				(font
					(size 1 1)
					(thickness 0.15)
				)
				(justify mirror)
			)
		)
		(property "License" "Apache-2.0"
			(at 0 0 0)
			(layer "B.Fab")
			(hide yes)
			(effects
				(font
					(size 1 1)
					(thickness 0.15)
				)
				(justify mirror)
			)
		)
		(property "MPN" "BLM18PG121SN1D"
			(at 0 0 0)
			(layer "B.Fab")
			(hide yes)
			(effects
				(font
					(size 1 1)
					(thickness 0.15)
				)
				(justify mirror)
			)
		)
		(property "Manufacturer" "Murata"
			(at 0 0 0)
			(layer "B.Fab")
			(hide yes)
			(effects
				(font
					(size 1 1)
					(thickness 0.15)
				)
				(justify mirror)
			)
		)
		(property "Val" "120Z/2A"
			(at 0 0 0)
			(unlocked yes)
			(layer "B.Fab")
			(hide yes)
			(effects
				(font
					(size 1 1)
					(thickness 0.15)
				)
				(justify mirror)
			)
		)
		(property "Current" ""
			(at 0 0 0)
			(unlocked yes)
			(layer "B.Fab")
			(hide yes)
			(effects
				(font
					(size 1 1)
					(thickness 0.15)
				)
				(justify mirror)
			)
		)
		(sheetname "/FPGA Power/")
		(sheetfile "FPGA_Power.kicad_sch")
		(attr smd)
		(fp_line
			(start -0.15 -0.4)
			(end 0.15 -0.4)
			(stroke
				(width 0.15)
				(type solid)
			)
			(layer "B.SilkS")
		)
		(fp_line
			(start -0.15 0.4)
			(end 0.15 0.4)
			(stroke
				(width 0.15)
				(type solid)
			)
			(layer "B.SilkS")
		)
		(fp_rect
			(start -1.25 0.65)
			(end 1.25 -0.65)
			(stroke
				(width 0.05)
				(type solid)
			)
			(fill no)
			(layer "B.CrtYd")
		)
		(fp_line
			(start -0.803 -0.406)
			(end -0.803 0.408)
			(stroke
				(width 0.15)
				(type solid)
			)
			(layer "B.Fab")
		)
		(fp_line
			(start 0.8 -0.406)
			(end -0.803 -0.406)
			(stroke
				(width 0.15)
				(type solid)
			)
			(layer "B.Fab")
		)
		(fp_line
			(start 0.8 0.408)
			(end -0.803 0.408)
			(stroke
				(width 0.15)
				(type solid)
			)
			(layer "B.Fab")
		)
		(fp_line
			(start 0.8 0.408)
			(end 0.8 -0.406)
			(stroke
				(width 0.15)
				(type solid)
			)
			(layer "B.Fab")
		)
		(fp_text user "License: Apache-2.0"
			(at -1.653 -5.9 180)
			(layer "B.Fab")
			(effects
				(font
					(size 0.7 0.7)
					(thickness 0.15)
				)
				(justify left bottom mirror)
			)
		)
		(fp_text user "${REFERENCE}"
			(at -1.653 -4.6 180)
			(layer "B.Fab")
			(effects
				(font
					(size 0.7 0.7)
					(thickness 0.15)
				)
				(justify left bottom mirror)
			)
		)
		(fp_text user "Author: Antmicro"
			(at -1.653 -3.162 180)
			(layer "B.Fab")
			(effects
				(font
					(size 0.7 0.7)
					(thickness 0.15)
				)
				(justify left bottom mirror)
			)
		)
		(pad "1" smd roundrect
			(at -0.7 0)
			(size 0.8 1)
			(layers "B.Cu" "B.Mask" "B.Paste")
			(roundrect_rratio 0.2)
			(net 9 "/FPGA Power/VCC_AUX")
			(pintype "passive")
		)
		(pad "2" smd roundrect
			(at 0.7 0)
			(size 0.8 1)
			(layers "B.Cu" "B.Mask" "B.Paste")
			(roundrect_rratio 0.2)
			(net 50 "+1V8")
			(pintype "passive")
		)
	)
	(footprint "antmicro-footprints:C_0402_1005Metric"
		(layer "B.Cu")
		(at 89.3 74.4)
		(descr "Capacitor SMD 0402")
		(tags "capacitor SMD 0402")
		(property "Reference" "C64"
			(at -1.27 1.34 0)
			(layer "B.SilkS")
			(effects
				(font
					(size 0.65 0.65)
					(thickness 0.15)
				)
				(justify right bottom mirror)
			)
		)
		(property "Value" "C_100n_0402"
			(at 0 -1.4 0)
			(layer "B.Fab")
			(hide yes)
			(effects
				(font
					(size 0.7 0.7)
					(thickness 0.15)
				)
				(justify right bottom mirror)
			)
		)
		(property "Datasheet" "https://www.murata.com/products/productdetail?partno=GRM155R61H104KE14%23"
			(at 0 0 0)
			(layer "F.Fab")
			(hide yes)
			(effects
				(font
					(size 1.27 1.27)
					(thickness 0.15)
				)
			)
		)
		(property "Description" "SMD Multilayer Ceramic Capacitor, 0.1 µF, 50 V, 0402 [1005 Metric], ± 10%, X5R, GRM Series"
			(at 0 0 0)
			(layer "F.Fab")
			(hide yes)
			(effects
				(font
					(size 1.27 1.27)
					(thickness 0.15)
				)
			)
		)
		(property "Author" "Antmicro"
			(at 0 0 0)
			(layer "B.Fab")
			(hide yes)
			(effects
				(font
					(size 1 1)
					(thickness 0.15)
				)
				(justify mirror)
			)
		)
		(property "Dielectric" "X5R"
			(at 0 0 0)
			(layer "B.Fab")
			(hide yes)
			(effects
				(font
					(size 1 1)
					(thickness 0.15)
				)
				(justify mirror)
			)
		)
		(property "License" "Apache-2.0"
			(at 0 0 0)
			(layer "B.Fab")
			(hide yes)
			(effects
				(font
					(size 1 1)
					(thickness 0.15)
				)
				(justify mirror)
			)
		)
		(property "MPN" "GRM155R61H104KE14D"
			(at 0 0 0)
			(layer "B.Fab")
			(hide yes)
			(effects
				(font
					(size 1 1)
					(thickness 0.15)
				)
				(justify mirror)
			)
		)
		(property "Manufacturer" "Murata"
			(at 0 0 0)
			(layer "B.Fab")
			(hide yes)
			(effects
				(font
					(size 1 1)
					(thickness 0.15)
				)
				(justify mirror)
			)
		)
		(property "Val" "100n"
			(at 0 0 0)
			(layer "B.Fab")
			(hide yes)
			(effects
				(font
					(size 1 1)
					(thickness 0.15)
				)
				(justify mirror)
			)
		)
		(property "Voltage" "50V"
			(at 0 0 0)
			(layer "B.Fab")
			(hide yes)
			(effects
				(font
					(size 1 1)
					(thickness 0.15)
				)
				(justify mirror)
			)
		)
		(sheetname "/SDI/")
		(sheetfile "sdi.kicad_sch")
		(attr smd)
		(fp_rect
			(start -0.925 0.47)
			(end 0.925 -0.47)
			(stroke
				(width 0.05)
				(type default)
			)
			(fill no)
			(layer "B.CrtYd")
		)
		(fp_line
			(start -0.494 -0.248)
			(end -0.494 0.25)
			(stroke
				(width 0.15)
				(type solid)
			)
			(layer "B.Fab")
		)
		(fp_line
			(start -0.494 0.25)
			(end 0.504 0.25)
			(stroke
				(width 0.15)
				(type solid)
			)
			(layer "B.Fab")
		)
		(fp_line
			(start 0.504 -0.248)
			(end -0.494 -0.248)
			(stroke
				(width 0.15)
				(type solid)
			)
			(layer "B.Fab")
		)
		(fp_line
			(start 0.504 0.25)
			(end 0.504 -0.248)
			(stroke
				(width 0.15)
				(type solid)
			)
			(layer "B.Fab")
		)
		(fp_text user "License: Apache-2.0"
			(at -0.939 -5.799 180)
			(layer "B.Fab")
			(effects
				(font
					(size 0.7 0.7)
					(thickness 0.15)
				)
				(justify left bottom mirror)
			)
		)
		(fp_text user "${REFERENCE}"
			(at -0.939 -4.599 180)
			(layer "B.Fab")
			(effects
				(font
					(size 0.7 0.7)
					(thickness 0.15)
				)
				(justify left bottom mirror)
			)
		)
		(fp_text user "Author: Antmicro"
			(at -0.939 -3.399 180)
			(layer "B.Fab")
			(effects
				(font
					(size 0.7 0.7)
					(thickness 0.15)
				)
				(justify left bottom mirror)
			)
		)
		(pad "1" smd roundrect
			(at -0.48 0)
			(size 0.59 0.64)
			(layers "B.Cu" "B.Mask" "B.Paste")
			(roundrect_rratio 0.25)
			(net 1 "GND")
			(pintype "passive")
		)
		(pad "2" smd roundrect
			(at 0.48 0)
			(size 0.59 0.64)
			(layers "B.Cu" "B.Mask" "B.Paste")
			(roundrect_rratio 0.25)
			(net 2 "+3V3")
			(pintype "passive")
		)
	)
)
